(kicad_pcb
	(version 20260206)
	(generator "pcbnew")
	(generator_version "10.0")
	(general
		(thickness 1.6)
		(legacy_teardrops no)
	)
	(paper "A4")
	(title_block
		(title "03242023_DA0F0TMBIJ0_F0T_Motherboard_J_brd_V01_OCP.brd")
		(comment 1 "Grand Teton / footprints 2966-2972 of 6105")
	)
	(layers
		(0 "F.Cu" signal "TOP")
		(4 "In1.Cu" signal "GND")
		(6 "In2.Cu" signal "IN1")
		(8 "In3.Cu" signal "GND1")
		(10 "In4.Cu" signal "IN2")
		(12 "In5.Cu" signal "GND2")
		(14 "In6.Cu" signal "IN3")
		(16 "In7.Cu" signal "GND3")
		(18 "In8.Cu" signal "VCC")
		(20 "In9.Cu" signal "VCC1")
		(22 "In10.Cu" signal "GND4")
		(24 "In11.Cu" signal "IN4")
		(26 "In12.Cu" signal "GND5")
		(28 "In13.Cu" signal "IN5")
		(30 "In14.Cu" signal "GND6")
		(32 "In15.Cu" signal "IN6")
		(34 "In16.Cu" signal "GND7")
		(2 "B.Cu" signal "BOTTOM")
		(9 "F.Adhes" user "F.Adhesive")
		(11 "B.Adhes" user "B.Adhesive")
		(13 "F.Paste" user "Package Geometry/Pastemask Top")
		(15 "B.Paste" user "Package Geometry/Pastemask Bottom")
		(5 "F.SilkS" user "Ref Des/Silkscreen Top")
		(7 "B.SilkS" user "Ref Des/Silkscreen Bottom")
		(1 "F.Mask" user "Board Geometry/Soldermask Top")
		(3 "B.Mask" user "Board Geometry/Soldermask Bottom")
		(17 "Dwgs.User" user "User.Drawings")
		(19 "Cmts.User" user "User.Comments")
		(21 "Eco1.User" user "User.Eco1")
		(23 "Eco2.User" user "User.Eco2")
		(25 "Edge.Cuts" user "Board Geometry/Outline")
		(27 "Margin" user)
		(31 "F.CrtYd" user "Package Geometry/Place Bound Top")
		(29 "B.CrtYd" user "Package Geometry/Place Bound Bottom")
		(35 "F.Fab" user "Ref Des/Assembly Top")
		(33 "B.Fab" user "Ref Des/Assembly Bottom")
	)
	(footprint ""
		(layer "F.Cu")
		(at 386.849366 -394.643356)
		(property "Reference" "ME20"
			(at 0 0 0)
			(layer "F.SilkS")
			(hide yes)
			(effects
				(font
					(size 1.27 1.27)
				)
			)
		)
		(property "Value" ""
			(at 0 0 0)
			(layer "F.Fab")
			(effects
				(font
					(size 1.27 1.27)
				)
			)
		)
		(duplicate_pad_numbers_are_jumpers no)
	)
	(footprint ""
		(layer "F.Cu")
		(at 230.960422 -117.710712 -90)
		(property "Reference" "R1275"
			(at 0 0 270)
			(layer "F.SilkS")
			(hide yes)
			(effects
				(font
					(size 1.27 1.27)
				)
			)
		)
		(property "Value" ""
			(at 0 0 270)
			(layer "F.Fab")
			(effects
				(font
					(size 1.27 1.27)
				)
			)
		)
		(duplicate_pad_numbers_are_jumpers no)
		(fp_line
			(start -0.7874 0.4064)
			(end -0.7874 0.000762)
			(stroke
				(width 0.1524)
				(type default)
			)
			(layer "F.SilkS")
		)
		(fp_line
			(start 0.7874 0.4064)
			(end -0.7874 0.4064)
			(stroke
				(width 0.1524)
				(type default)
			)
			(layer "F.SilkS")
		)
		(fp_line
			(start 0.7874 -0.095758)
			(end 0.7874 0.4064)
			(stroke
				(width 0.1524)
				(type default)
			)
			(layer "F.SilkS")
		)
		(fp_line
			(start -0.373888 -0.4064)
			(end 0.418592 -0.4064)
			(stroke
				(width 0.1524)
				(type default)
			)
			(layer "F.SilkS")
		)
		(fp_line
			(start -0.67945 0.3048)
			(end -0.67945 -0.305054)
			(stroke
				(width 0.1)
				(type default)
			)
			(layer "F.Fab")
		)
		(fp_line
			(start -0.12065 0.3048)
			(end -0.67945 0.3048)
			(stroke
				(width 0.1)
				(type default)
			)
			(layer "F.Fab")
		)
		(fp_line
			(start 0.120396 0.3048)
			(end 0.120396 0.2794)
			(stroke
				(width 0.1)
				(type default)
			)
			(layer "F.Fab")
		)
		(fp_line
			(start 0.67945 0.3048)
			(end 0.120396 0.3048)
			(stroke
				(width 0.1)
				(type default)
			)
			(layer "F.Fab")
		)
		(fp_line
			(start -0.12065 0.2794)
			(end -0.12065 0.3048)
			(stroke
				(width 0.1)
				(type default)
			)
			(layer "F.Fab")
		)
		(fp_line
			(start 0.120396 0.2794)
			(end -0.12065 0.2794)
			(stroke
				(width 0.1)
				(type default)
			)
			(layer "F.Fab")
		)
		(fp_line
			(start -0.12065 -0.2794)
			(end 0.12065 -0.2794)
			(stroke
				(width 0.1)
				(type default)
			)
			(layer "F.Fab")
		)
		(fp_line
			(start 0.12065 -0.2794)
			(end 0.12065 -0.3048)
			(stroke
				(width 0.1)
				(type default)
			)
			(layer "F.Fab")
		)
		(fp_line
			(start 0.12065 -0.3048)
			(end 0.67945 -0.3048)
			(stroke
				(width 0.1)
				(type default)
			)
			(layer "F.Fab")
		)
		(fp_line
			(start 0.67945 -0.3048)
			(end 0.67945 0.3048)
			(stroke
				(width 0.1)
				(type default)
			)
			(layer "F.Fab")
		)
		(fp_line
			(start -0.67945 -0.305054)
			(end -0.12065 -0.305054)
			(stroke
				(width 0.1)
				(type default)
			)
			(layer "F.Fab")
		)
		(fp_line
			(start -0.12065 -0.305054)
			(end -0.12065 -0.2794)
			(stroke
				(width 0.1)
				(type default)
			)
			(layer "F.Fab")
		)
		(pad "1" smd circle
			(at -0.40005 0 270)
			(size 0 0)
			(layers "F.Cu" "F.Mask" "F.Paste")
			(net "CLK_100M_OCP_SFF_3_R_DP")
		)
		(pad "2" smd circle
			(at 0.40005 0 270)
			(size 0 0)
			(layers "F.Cu" "F.Mask" "F.Paste")
			(net "CLK_100M_OCP_SFF_3_DP")
		)
	)
	(footprint ""
		(layer "F.Cu")
		(at 433.83962 -175.197008 90)
		(property "Reference" "PC1420"
			(at 0 0 90)
			(layer "F.SilkS")
			(hide yes)
			(effects
				(font
					(size 1.27 1.27)
				)
			)
		)
		(property "Value" ""
			(at 0 0 90)
			(layer "F.Fab")
			(effects
				(font
					(size 1.27 1.27)
				)
			)
		)
		(duplicate_pad_numbers_are_jumpers no)
		(fp_line
			(start 0.7874 -0.4064)
			(end 0.7874 0.4064)
			(stroke
				(width 0.1524)
				(type default)
			)
			(layer "F.SilkS")
		)
		(fp_line
			(start -0.7874 -0.4064)
			(end 0.7874 -0.4064)
			(stroke
				(width 0.1524)
				(type default)
			)
			(layer "F.SilkS")
		)
		(fp_line
			(start 0.7874 0.4064)
			(end -0.7874 0.4064)
			(stroke
				(width 0.1524)
				(type default)
			)
			(layer "F.SilkS")
		)
		(fp_line
			(start -0.7874 0.4064)
			(end -0.7874 -0.4064)
			(stroke
				(width 0.1524)
				(type default)
			)
			(layer "F.SilkS")
		)
		(fp_line
			(start -0.12065 -0.305054)
			(end -0.12065 -0.2794)
			(stroke
				(width 0.1)
				(type default)
			)
			(layer "F.Fab")
		)
		(fp_line
			(start -0.67945 -0.305054)
			(end -0.12065 -0.305054)
			(stroke
				(width 0.1)
				(type default)
			)
			(layer "F.Fab")
		)
		(fp_line
			(start 0.67945 -0.3048)
			(end 0.67945 0.3048)
			(stroke
				(width 0.1)
				(type default)
			)
			(layer "F.Fab")
		)
		(fp_line
			(start 0.12065 -0.3048)
			(end 0.67945 -0.3048)
			(stroke
				(width 0.1)
				(type default)
			)
			(layer "F.Fab")
		)
		(fp_line
			(start 0.12065 -0.2794)
			(end 0.12065 -0.3048)
			(stroke
				(width 0.1)
				(type default)
			)
			(layer "F.Fab")
		)
		(fp_line
			(start -0.12065 -0.2794)
			(end 0.12065 -0.2794)
			(stroke
				(width 0.1)
				(type default)
			)
			(layer "F.Fab")
		)
		(fp_line
			(start 0.120396 0.2794)
			(end -0.12065 0.2794)
			(stroke
				(width 0.1)
				(type default)
			)
			(layer "F.Fab")
		)
		(fp_line
			(start -0.12065 0.2794)
			(end -0.12065 0.3048)
			(stroke
				(width 0.1)
				(type default)
			)
			(layer "F.Fab")
		)
		(fp_line
			(start 0.67945 0.3048)
			(end 0.120396 0.3048)
			(stroke
				(width 0.1)
				(type default)
			)
			(layer "F.Fab")
		)
		(fp_line
			(start 0.120396 0.3048)
			(end 0.120396 0.2794)
			(stroke
				(width 0.1)
				(type default)
			)
			(layer "F.Fab")
		)
		(fp_line
			(start -0.12065 0.3048)
			(end -0.67945 0.3048)
			(stroke
				(width 0.1)
				(type default)
			)
			(layer "F.Fab")
		)
		(fp_line
			(start -0.67945 0.3048)
			(end -0.67945 -0.305054)
			(stroke
				(width 0.1)
				(type default)
			)
			(layer "F.Fab")
		)
		(pad "1" smd circle
			(at -0.40005 0 90)
			(size 0 0)
			(layers "F.Cu" "F.Mask" "F.Paste")
			(net "PVNN_MAIN_CPU0_FB_RC")
		)
		(pad "2" smd circle
			(at 0.40005 0 90)
			(size 0 0)
			(layers "F.Cu" "F.Mask" "F.Paste")
			(net "GND")
		)
	)
	(footprint ""
		(layer "F.Cu")
		(at 240.854484 -55.612792 180)
		(property "Reference" "C1992"
			(at 0 0 180)
			(layer "F.SilkS")
			(hide yes)
			(effects
				(font
					(size 1.27 1.27)
				)
			)
		)
		(property "Value" ""
			(at 0 0 180)
			(layer "F.Fab")
			(effects
				(font
					(size 1.27 1.27)
				)
			)
		)
		(duplicate_pad_numbers_are_jumpers no)
		(fp_line
			(start 0.299974 0.150114)
			(end -0.299974 0.150114)
			(stroke
				(width 0.1)
				(type default)
			)
			(layer "F.Fab")
		)
		(fp_line
			(start 0.299974 -0.150114)
			(end 0.299974 0.150114)
			(stroke
				(width 0.1)
				(type default)
			)
			(layer "F.Fab")
		)
		(fp_line
			(start -0.299974 0.150114)
			(end -0.299974 -0.150114)
			(stroke
				(width 0.1)
				(type default)
			)
			(layer "F.Fab")
		)
		(fp_line
			(start -0.299974 -0.150114)
			(end 0.299974 -0.150114)
			(stroke
				(width 0.1)
				(type default)
			)
			(layer "F.Fab")
		)
		(pad "1" smd rect
			(at -0.2667 0 180)
			(size 0.3048 0.381)
			(layers "F.Cu" "F.Mask" "F.Paste")
			(net "P3E_PCH_E1S_TX_DN<2>")
		)
		(pad "2" smd rect
			(at 0.2667 0 180)
			(size 0.3048 0.381)
			(layers "F.Cu" "F.Mask" "F.Paste")
			(net "P3E_PCH_E1S_TX_C_DN<2>")
		)
		(zone
			(layer "In1.Cu")
			(hatch none 0.5)
			(connect_pads
				(clearance 0)
			)
			(min_thickness 0.25)
			(keepout
				(tracks not_allowed)
				(vias allowed)
				(pads allowed)
				(copperpour not_allowed)
				(footprints allowed)
			)
			(placement
				(enabled no)
				(sheetname "")
			)
			(fill
				(thermal_gap 0.5)
				(thermal_bridge_width 0.5)
				(island_removal_mode 0)
			)
			(polygon
				(pts
					(arc
						(start 240.714784 -55.853076)
						(mid 240.768666 -55.830758)
						(end 240.790984 -55.776876)
					)
					(arc
						(start 240.790984 -55.446676)
						(mid 240.768666 -55.392794)
						(end 240.714784 -55.370476)
					)
					(arc
						(start 240.460784 -55.370476)
						(mid 240.406902 -55.392794)
						(end 240.384584 -55.446676)
					)
					(arc
						(start 240.384584 -55.776876)
						(mid 240.406902 -55.830758)
						(end 240.460784 -55.853076)
					)
				)
			)
		)
		(zone
			(layer "In1.Cu")
			(hatch none 0.5)
			(connect_pads
				(clearance 0)
			)
			(min_thickness 0.25)
			(keepout
				(tracks not_allowed)
				(vias allowed)
				(pads allowed)
				(copperpour not_allowed)
				(footprints allowed)
			)
			(placement
				(enabled no)
				(sheetname "")
			)
			(fill
				(thermal_gap 0.5)
				(thermal_bridge_width 0.5)
				(island_removal_mode 0)
			)
			(polygon
				(pts
					(arc
						(start 241.248184 -55.853076)
						(mid 241.302066 -55.830758)
						(end 241.324384 -55.776876)
					)
					(arc
						(start 241.324384 -55.446676)
						(mid 241.302066 -55.392794)
						(end 241.248184 -55.370476)
					)
					(arc
						(start 240.994184 -55.370476)
						(mid 240.940302 -55.392794)
						(end 240.917984 -55.446676)
					)
					(arc
						(start 240.917984 -55.776876)
						(mid 240.940302 -55.830758)
						(end 240.994184 -55.853076)
					)
				)
			)
		)
	)
	(footprint ""
		(layer "F.Cu")
		(at 126.385828 -350.780858)
		(property "Reference" "PC1261"
			(at 0 0 0)
			(layer "F.SilkS")
			(hide yes)
			(effects
				(font
					(size 1.27 1.27)
				)
			)
		)
		(property "Value" ""
			(at 0 0 0)
			(layer "F.Fab")
			(effects
				(font
					(size 1.27 1.27)
				)
			)
		)
		(duplicate_pad_numbers_are_jumpers no)
		(fp_line
			(start -1.524 -0.762)
			(end 1.524 -0.762)
			(stroke
				(width 0.1524)
				(type default)
			)
			(layer "F.SilkS")
		)
		(fp_line
			(start -1.524 0.762)
			(end -1.524 -0.762)
			(stroke
				(width 0.1524)
				(type default)
			)
			(layer "F.SilkS")
		)
		(fp_line
			(start 1.524 -0.762)
			(end 1.524 0.762)
			(stroke
				(width 0.1524)
				(type default)
			)
			(layer "F.SilkS")
		)
		(fp_line
			(start 1.524 0.762)
			(end -1.524 0.762)
			(stroke
				(width 0.1524)
				(type default)
			)
			(layer "F.SilkS")
		)
		(fp_line
			(start -1.1049 -0.724916)
			(end -1.1049 0.724916)
			(stroke
				(width 0.1)
				(type default)
			)
			(layer "F.Fab")
		)
		(fp_line
			(start -1.1049 0.724916)
			(end 1.1049 0.724916)
			(stroke
				(width 0.1)
				(type default)
			)
			(layer "F.Fab")
		)
		(fp_line
			(start 1.1049 -0.724916)
			(end -1.1049 -0.724916)
			(stroke
				(width 0.1)
				(type default)
			)
			(layer "F.Fab")
		)
		(fp_line
			(start 1.1049 0.724916)
			(end 1.1049 -0.724916)
			(stroke
				(width 0.1)
				(type default)
			)
			(layer "F.Fab")
		)
		(pad "1" smd rect
			(at -0.889 0 180)
			(size 1.016 1.27)
			(layers "F.Cu" "F.Mask" "F.Paste")
			(net "SW_P12V_PVCCIN_CPU1_FLT")
		)
		(pad "2" smd rect
			(at 0.889 0 180)
			(size 1.016 1.27)
			(layers "F.Cu" "F.Mask" "F.Paste")
			(net "GND")
		)
	)
	(footprint ""
		(layer "F.Cu")
		(at 143.764 -26.126948 180)
		(property "Reference" "R4627"
			(at 0 0 180)
			(layer "F.SilkS")
			(hide yes)
			(effects
				(font
					(size 1.27 1.27)
				)
			)
		)
		(property "Value" ""
			(at 0 0 180)
			(layer "F.Fab")
			(effects
				(font
					(size 1.27 1.27)
				)
			)
		)
		(duplicate_pad_numbers_are_jumpers no)
		(fp_line
			(start 0.7874 0.4064)
			(end -0.7874 0.4064)
			(stroke
				(width 0.1524)
				(type default)
			)
			(layer "F.SilkS")
		)
		(fp_line
			(start 0.7874 -0.4064)
			(end 0.7874 0.4064)
			(stroke
				(width 0.1524)
				(type default)
			)
			(layer "F.SilkS")
		)
		(fp_line
			(start -0.7874 0.4064)
			(end -0.7874 -0.4064)
			(stroke
				(width 0.1524)
				(type default)
			)
			(layer "F.SilkS")
		)
		(fp_line
			(start -0.7874 -0.4064)
			(end 0.7874 -0.4064)
			(stroke
				(width 0.1524)
				(type default)
			)
			(layer "F.SilkS")
		)
		(fp_line
			(start 0.67945 0.3048)
			(end 0.120396 0.3048)
			(stroke
				(width 0.1)
				(type default)
			)
			(layer "F.Fab")
		)
		(fp_line
			(start 0.67945 -0.3048)
			(end 0.67945 0.3048)
			(stroke
				(width 0.1)
				(type default)
			)
			(layer "F.Fab")
		)
		(fp_line
			(start 0.12065 -0.2794)
			(end 0.12065 -0.3048)
			(stroke
				(width 0.1)
				(type default)
			)
			(layer "F.Fab")
		)
		(fp_line
			(start 0.12065 -0.3048)
			(end 0.67945 -0.3048)
			(stroke
				(width 0.1)
				(type default)
			)
			(layer "F.Fab")
		)
		(fp_line
			(start 0.120396 0.3048)
			(end 0.120396 0.2794)
			(stroke
				(width 0.1)
				(type default)
			)
			(layer "F.Fab")
		)
		(fp_line
			(start 0.120396 0.2794)
			(end -0.12065 0.2794)
			(stroke
				(width 0.1)
				(type default)
			)
			(layer "F.Fab")
		)
		(fp_line
			(start -0.12065 0.3048)
			(end -0.67945 0.3048)
			(stroke
				(width 0.1)
				(type default)
			)
			(layer "F.Fab")
		)
		(fp_line
			(start -0.12065 0.2794)
			(end -0.12065 0.3048)
			(stroke
				(width 0.1)
				(type default)
			)
			(layer "F.Fab")
		)
		(fp_line
			(start -0.12065 -0.2794)
			(end 0.12065 -0.2794)
			(stroke
				(width 0.1)
				(type default)
			)
			(layer "F.Fab")
		)
		(fp_line
			(start -0.12065 -0.305054)
			(end -0.12065 -0.2794)
			(stroke
				(width 0.1)
				(type default)
			)
			(layer "F.Fab")
		)
		(fp_line
			(start -0.67945 0.3048)
			(end -0.67945 -0.305054)
			(stroke
				(width 0.1)
				(type default)
			)
			(layer "F.Fab")
		)
		(fp_line
			(start -0.67945 -0.305054)
			(end -0.12065 -0.305054)
			(stroke
				(width 0.1)
				(type default)
			)
			(layer "F.Fab")
		)
		(pad "1" smd circle
			(at -0.40005 0 180)
			(size 0 0)
			(layers "F.Cu" "F.Mask" "F.Paste")
			(net "JTAG_BMC_TDI")
		)
		(pad "2" smd circle
			(at 0.40005 0 180)
			(size 0 0)
			(layers "F.Cu" "F.Mask" "F.Paste")
			(net "JTAG_BMC_TDI_R")
		)
	)
	(footprint ""
		(layer "F.Cu")
		(at 115.95608 -122.132598 90)
		(property "Reference" "R936"
			(at 0 0 90)
			(layer "F.SilkS")
			(hide yes)
			(effects
				(font
					(size 1.27 1.27)
				)
			)
		)
		(property "Value" ""
			(at 0 0 90)
			(layer "F.Fab")
			(effects
				(font
					(size 1.27 1.27)
				)
			)
		)
		(duplicate_pad_numbers_are_jumpers no)
		(fp_line
			(start 0.7874 -0.4064)
			(end 0.7874 0.4064)
			(stroke
				(width 0.1524)
				(type default)
			)
			(layer "F.SilkS")
		)
		(fp_line
			(start -0.7874 -0.4064)
			(end 0.7874 -0.4064)
			(stroke
				(width 0.1524)
				(type default)
			)
			(layer "F.SilkS")
		)
		(fp_line
			(start 0.7874 0.4064)
			(end -0.7874 0.4064)
			(stroke
				(width 0.1524)
				(type default)
			)
			(layer "F.SilkS")
		)
		(fp_line
			(start -0.7874 0.4064)
			(end -0.7874 -0.4064)
			(stroke
				(width 0.1524)
				(type default)
			)
			(layer "F.SilkS")
		)
		(fp_line
			(start -0.12065 -0.305054)
			(end -0.12065 -0.2794)
			(stroke
				(width 0.1)
				(type default)
			)
			(layer "F.Fab")
		)
		(fp_line
			(start -0.67945 -0.305054)
			(end -0.12065 -0.305054)
			(stroke
				(width 0.1)
				(type default)
			)
			(layer "F.Fab")
		)
		(fp_line
			(start 0.67945 -0.3048)
			(end 0.67945 0.3048)
			(stroke
				(width 0.1)
				(type default)
			)
			(layer "F.Fab")
		)
		(fp_line
			(start 0.12065 -0.3048)
			(end 0.67945 -0.3048)
			(stroke
				(width 0.1)
				(type default)
			)
			(layer "F.Fab")
		)
		(fp_line
			(start 0.12065 -0.2794)
			(end 0.12065 -0.3048)
			(stroke
				(width 0.1)
				(type default)
			)
			(layer "F.Fab")
		)
		(fp_line
			(start -0.12065 -0.2794)
			(end 0.12065 -0.2794)
			(stroke
				(width 0.1)
				(type default)
			)
			(layer "F.Fab")
		)
		(fp_line
			(start 0.120396 0.2794)
			(end -0.12065 0.2794)
			(stroke
				(width 0.1)
				(type default)
			)
			(layer "F.Fab")
		)
		(fp_line
			(start -0.12065 0.2794)
			(end -0.12065 0.3048)
			(stroke
				(width 0.1)
				(type default)
			)
			(layer "F.Fab")
		)
		(fp_line
			(start 0.67945 0.3048)
			(end 0.120396 0.3048)
			(stroke
				(width 0.1)
				(type default)
			)
			(layer "F.Fab")
		)
		(fp_line
			(start 0.120396 0.3048)
			(end 0.120396 0.2794)
			(stroke
				(width 0.1)
				(type default)
			)
			(layer "F.Fab")
		)
		(fp_line
			(start -0.12065 0.3048)
			(end -0.67945 0.3048)
			(stroke
				(width 0.1)
				(type default)
			)
			(layer "F.Fab")
		)
		(fp_line
			(start -0.67945 0.3048)
			(end -0.67945 -0.305054)
			(stroke
				(width 0.1)
				(type default)
			)
			(layer "F.Fab")
		)
		(pad "1" smd circle
			(at -0.40005 0 90)
			(size 0 0)
			(layers "F.Cu" "F.Mask" "F.Paste")
			(net "RST_CPU0_DRAM_EF_N")
		)
		(pad "2" smd circle
			(at 0.40005 0 90)
			(size 0 0)
			(layers "F.Cu" "F.Mask" "F.Paste")
			(net "GND")
		)
	)
)
